(kicad_pcb
	(version 20260206)
	(generator "pcbnew")
	(generator_version "10.0")
	(general
		(thickness 1.21888)
		(legacy_teardrops no)
	)
	(paper "A4")
	(title_block
		(title "timecard-v7 — TimeCard-DC-V7_EXP.PcbDoc")
		(comment 1 "Time Appliance Project (Time Card) / footprints 137-147 of 160")
	)
	(layers
		(0 "F.Cu" signal "TOP")
		(4 "In1.Cu" signal "SGND")
		(6 "In2.Cu" signal "IN1")
		(8 "In3.Cu" signal "IN2")
		(10 "In4.Cu" signal "SGND1")
		(2 "B.Cu" signal "BOTTOM")
		(9 "F.Adhes" user "F.Adhesive")
		(11 "B.Adhes" user "B.Adhesive")
		(13 "F.Paste" user "Top Paste")
		(15 "B.Paste" user "Bottom Paste")
		(5 "F.SilkS" user "Top Overlay")
		(7 "B.SilkS" user "Bottom Overlay")
		(1 "F.Mask" user "Top Solder")
		(3 "B.Mask" user "Bottom Solder")
		(17 "Dwgs.User" user "User.Drawings")
		(19 "Cmts.User" user "User.Comments")
		(21 "Eco1.User" user "User.Eco1")
		(23 "Eco2.User" user "User.Eco2")
		(25 "Edge.Cuts" user)
		(27 "Margin" user)
		(31 "F.CrtYd" user "Top Courtyard")
		(29 "B.CrtYd" user "Bottom Courtyard")
		(35 "F.Fab" user "Top Component Center")
		(33 "B.Fab" user "Bottom Component Center")
	)
	(footprint "Vault:FP-LTST-C191TBKT-MFG"
		(layer "F.Cu")
		(at 75.1261 52.1162 90)
		(property "Reference" "D11"
			(at -7.75 0.343345 90)
			(unlocked yes)
			(layer "F.SilkS")
			(effects
				(font
					(size 0.762 0.762)
					(thickness 0.2286)
				)
				(justify left bottom)
			)
		)
		(property "Value" "BLUE"
			(at -3.22199 -1.4097 0)
			(unlocked yes)
			(layer "F.SilkS")
			(hide yes)
			(effects
				(font
					(size 1.524 1.524)
					(thickness 0.254)
				)
				(justify left bottom)
			)
		)
		(sheetname "USER_IO_STATUS")
		(sheetfile "USER_IO_STATUS.kicad_sch")
		(duplicate_pad_numbers_are_jumpers no)
		(fp_line
			(start -0.85 -0.8)
			(end 0.85 -0.8)
			(stroke
				(width 0.2)
				(type solid)
			)
			(layer "F.SilkS")
		)
		(fp_line
			(start -0.85 0.8)
			(end 0.85 0.8)
			(stroke
				(width 0.2)
				(type solid)
			)
			(layer "F.SilkS")
		)
		(fp_circle
			(center -1.75 0)
			(end -1.625 0)
			(stroke
				(width 0.25)
				(type solid)
			)
			(fill no)
			(layer "F.SilkS")
		)
		(fp_line
			(start 1.25 -0.55)
			(end 1.25 0.55)
			(stroke
				(width 0.2)
				(type solid)
			)
			(layer "F.CrtYd")
		)
		(fp_line
			(start -1.25 -0.55)
			(end 1.25 -0.55)
			(stroke
				(width 0.2)
				(type solid)
			)
			(layer "F.CrtYd")
		)
		(fp_line
			(start -1.25 -0.55)
			(end -1.25 0.55)
			(stroke
				(width 0.2)
				(type solid)
			)
			(layer "F.CrtYd")
		)
		(fp_line
			(start -1.25 0.55)
			(end 1.25 0.55)
			(stroke
				(width 0.2)
				(type solid)
			)
			(layer "F.CrtYd")
		)
		(fp_line
			(start 1.25 -0.55)
			(end 1.25 0.55)
			(stroke
				(width 0.2)
				(type solid)
			)
			(layer "F.Fab")
		)
		(fp_line
			(start -1.25 -0.55)
			(end 1.25 -0.55)
			(stroke
				(width 0.2)
				(type solid)
			)
			(layer "F.Fab")
		)
		(fp_line
			(start -1.25 -0.55)
			(end -1.25 0.55)
			(stroke
				(width 0.2)
				(type solid)
			)
			(layer "F.Fab")
		)
		(fp_line
			(start 0 -0.5)
			(end 0 0.5)
			(stroke
				(width 0.1)
				(type solid)
			)
			(layer "F.Fab")
		)
		(fp_line
			(start -0.5 0)
			(end 0.5 0)
			(stroke
				(width 0.1)
				(type solid)
			)
			(layer "F.Fab")
		)
		(fp_line
			(start -1.25 0.55)
			(end 1.25 0.55)
			(stroke
				(width 0.2)
				(type solid)
			)
			(layer "F.Fab")
		)
		(pad "1" smd rect
			(at -0.75 0 90)
			(size 0.8 0.8)
			(layers "F.Cu" "F.Mask" "F.Paste")
			(net "NetD11_1")
			(solder_mask_margin 0)
			(solder_paste_margin 0)
		)
		(pad "2" smd rect
			(at 0.75 0 90)
			(size 0.8 0.8)
			(layers "F.Cu" "F.Mask" "F.Paste")
			(net "+3.3V")
			(solder_mask_margin 0)
			(solder_paste_margin 0)
		)
	)
	(footprint "Resistors:RESC1608X50N"
		(layer "F.Cu")
		(at 210.9885 113.6662 90)
		(property "Reference" "R6"
			(at -3.398 0.321345 90)
			(unlocked yes)
			(layer "F.SilkS")
			(effects
				(font
					(size 0.762 0.762)
					(thickness 0.2286)
				)
				(justify left bottom)
			)
		)
		(property "Value" "ERJ-3EKF1002V"
			(at -1.35659 -0.8447 0)
			(unlocked yes)
			(layer "F.SilkS")
			(hide yes)
			(effects
				(font
					(size 1.524 1.524)
					(thickness 0.254)
				)
				(justify left bottom)
			)
		)
		(sheetname "POWER")
		(sheetfile "POWER.kicad_sch")
		(duplicate_pad_numbers_are_jumpers no)
		(fp_line
			(start 0 -0.5)
			(end 0 0.5)
			(stroke
				(width 0.1524)
				(type solid)
			)
			(layer "F.SilkS")
		)
		(pad "1" smd rect
			(at -0.69 0 180)
			(size 1 0.72)
			(layers "F.Cu" "F.Mask" "F.Paste")
			(net "GND")
		)
		(pad "2" smd rect
			(at 0.69 0 180)
			(size 1 0.72)
			(layers "F.Cu" "F.Mask" "F.Paste")
			(net "NetR4_2")
		)
	)
	(footprint "Vault:RESC1608X55X30NL15T15"
		(layer "F.Cu")
		(at 82.3761 125.8662 -90)
		(property "Reference" "R17"
			(at 2.7714 -0.026921 90)
			(unlocked yes)
			(layer "F.SilkS")
			(effects
				(font
					(size 0.762 0.762)
					(thickness 0.2286)
				)
			)
		)
		(property "Value" "4.7K"
			(at -2.911592 3.21199 180)
			(unlocked yes)
			(layer "F.SilkS")
			(hide yes)
			(effects
				(font
					(size 1.524 1.524)
					(thickness 0.254)
				)
			)
		)
		(sheetname "USER_IO")
		(sheetfile "USER_IO.kicad_sch")
		(duplicate_pad_numbers_are_jumpers no)
		(pad "1" smd rect
			(at -0.75 0)
			(size 0.95 0.95)
			(layers "F.Cu" "F.Mask" "F.Paste")
			(net "ANT3_IO_IN")
		)
		(pad "2" smd rect
			(at 0.75 0)
			(size 0.95 0.95)
			(layers "F.Cu" "F.Mask" "F.Paste")
			(net "+3.3V")
		)
	)
	(footprint "Vault:CAPC1608X87X45ML20T05"
		(layer "F.Cu")
		(at 203.9485 110.8452 -90)
		(property "Reference" "C19"
			(at 1.046 1.141655 90)
			(unlocked yes)
			(layer "F.SilkS")
			(effects
				(font
					(size 0.762 0.762)
					(thickness 0.2286)
				)
				(justify left bottom)
			)
		)
		(property "Value" "0.1uF"
			(at -1.94801 -9.4735 0)
			(unlocked yes)
			(layer "F.SilkS")
			(hide yes)
			(effects
				(font
					(size 1.524 1.524)
					(thickness 0.254)
				)
				(justify left bottom)
			)
		)
		(sheetname "POWER")
		(sheetfile "POWER.kicad_sch")
		(duplicate_pad_numbers_are_jumpers no)
		(pad "1" smd rect
			(at -0.7 0)
			(size 1.1 1.05)
			(layers "F.Cu" "F.Mask" "F.Paste")
			(net "GND")
		)
		(pad "2" smd rect
			(at 0.7 0)
			(size 1.1 1.05)
			(layers "F.Cu" "F.Mask" "F.Paste")
			(net "NetC19_2")
		)
	)
	(footprint "Vault:FP-C0603C105K3PACTU-MFG"
		(layer "F.Cu")
		(at 82.3761 86.9662 -90)
		(property "Reference" "C38"
			(at -0.3286 2.973069 90)
			(unlocked yes)
			(layer "F.SilkS")
			(effects
				(font
					(size 0.762 0.762)
					(thickness 0.2286)
				)
			)
		)
		(property "Value" "1uF"
			(at -2.886202 1.485285 180)
			(unlocked yes)
			(layer "F.SilkS")
			(hide yes)
			(effects
				(font
					(size 1.524 1.524)
					(thickness 0.254)
				)
			)
		)
		(sheetname "USER_IO_STATUS")
		(sheetfile "USER_IO_STATUS.kicad_sch")
		(duplicate_pad_numbers_are_jumpers no)
		(fp_line
			(start 0.875 0.825)
			(end -0.875 0.825)
			(stroke
				(width 0.2)
				(type solid)
			)
			(layer "F.SilkS")
		)
		(fp_line
			(start 0.875 -0.825)
			(end -0.875 -0.825)
			(stroke
				(width 0.2)
				(type solid)
			)
			(layer "F.SilkS")
		)
		(fp_line
			(start -1.2 0.6)
			(end -1.2 -0.6)
			(stroke
				(width 0.2)
				(type solid)
			)
			(layer "F.CrtYd")
		)
		(fp_line
			(start 1.2 0.6)
			(end -1.2 0.6)
			(stroke
				(width 0.2)
				(type solid)
			)
			(layer "F.CrtYd")
		)
		(fp_line
			(start 1.2 0.6)
			(end 1.2 -0.6)
			(stroke
				(width 0.2)
				(type solid)
			)
			(layer "F.CrtYd")
		)
		(fp_line
			(start 1.2 -0.6)
			(end -1.2 -0.6)
			(stroke
				(width 0.2)
				(type solid)
			)
			(layer "F.CrtYd")
		)
		(fp_line
			(start -1.2 0.6)
			(end -1.2 -0.6)
			(stroke
				(width 0.2)
				(type solid)
			)
			(layer "F.Fab")
		)
		(fp_line
			(start 1.2 0.6)
			(end -1.2 0.6)
			(stroke
				(width 0.2)
				(type solid)
			)
			(layer "F.Fab")
		)
		(fp_line
			(start 1.2 0.6)
			(end 1.2 -0.6)
			(stroke
				(width 0.2)
				(type solid)
			)
			(layer "F.Fab")
		)
		(fp_line
			(start 0 0.5)
			(end 0 -0.5)
			(stroke
				(width 0.1)
				(type solid)
			)
			(layer "F.Fab")
		)
		(fp_line
			(start 0.5 0)
			(end -0.5 0)
			(stroke
				(width 0.1)
				(type solid)
			)
			(layer "F.Fab")
		)
		(fp_line
			(start 1.2 -0.6)
			(end -1.2 -0.6)
			(stroke
				(width 0.2)
				(type solid)
			)
			(layer "F.Fab")
		)
		(pad "1" smd rect
			(at -0.6 0 270)
			(size 0.75 0.9)
			(layers "F.Cu" "F.Mask" "F.Paste")
			(net "+3.3V")
			(solder_mask_margin 0)
			(solder_paste_margin 0)
		)
		(pad "2" smd rect
			(at 0.6 0 270)
			(size 0.75 0.9)
			(layers "F.Cu" "F.Mask" "F.Paste")
			(net "GND")
			(solder_mask_margin 0)
			(solder_paste_margin 0)
		)
	)
	(footprint "SamacSys:155124M173200"
		(layer "F.Cu")
		(at 58.4511 71.6662 90)
		(property "Reference" "D13"
			(at -4.7 -0.231655 90)
			(unlocked yes)
			(layer "F.SilkS")
			(effects
				(font
					(size 0.762 0.762)
					(thickness 0.2286)
				)
				(justify left bottom)
			)
		)
		(property "Value" "155124M173200"
			(at -4.13639 -0.5715 0)
			(unlocked yes)
			(layer "F.SilkS")
			(hide yes)
			(effects
				(font
					(size 1.524 1.524)
					(thickness 0.254)
				)
				(justify left bottom)
			)
		)
		(sheetname "USER_IO_STATUS")
		(sheetfile "USER_IO_STATUS.kicad_sch")
		(duplicate_pad_numbers_are_jumpers no)
		(fp_line
			(start -0.8 0.5)
			(end 0.8 0.5)
			(stroke
				(width 0.1)
				(type solid)
			)
			(layer "F.SilkS")
		)
		(fp_arc
			(start -2 -0.1)
			(mid -1.95 -0.05)
			(end -2 0)
			(stroke
				(width 0.1)
				(type solid)
			)
			(layer "F.SilkS")
		)
		(fp_arc
			(start -2 0)
			(mid -2.05 -0.05)
			(end -2 -0.1)
			(stroke
				(width 0.1)
				(type solid)
			)
			(layer "F.SilkS")
		)
		(pad "1" smd rect
			(at -1.4 0 180)
			(size 0.9 0.6)
			(layers "F.Cu" "F.Mask" "F.Paste")
			(net "+3.3V")
		)
		(pad "2" smd rect
			(at -0.45 -0.325 90)
			(size 0.6 0.55)
			(layers "F.Cu" "F.Mask" "F.Paste")
			(net "NetD13_2")
		)
		(pad "3" smd rect
			(at 0.45 -0.325 90)
			(size 0.6 0.55)
			(layers "F.Cu" "F.Mask" "F.Paste")
			(net "NetD13_3")
		)
		(pad "4" smd rect
			(at 1.4 0 180)
			(size 0.9 0.6)
			(layers "F.Cu" "F.Mask" "F.Paste")
			(net "NetD13_4")
		)
	)
	(footprint "Vault:CAPC1608X87X45ML20T05"
		(layer "F.Cu")
		(at 190.1261 89.3786 90)
		(property "Reference" "C33"
			(at 3.2786 0.026921 90)
			(unlocked yes)
			(layer "F.SilkS")
			(effects
				(font
					(size 0.762 0.762)
					(thickness 0.2286)
				)
			)
		)
		(property "Value" "0.1uF"
			(at 2.09443 2.657602 90)
			(unlocked yes)
			(layer "F.SilkS")
			(hide yes)
			(effects
				(font
					(size 1.524 1.524)
					(thickness 0.254)
				)
			)
		)
		(sheetname "GPS_IMU_SENSORS")
		(sheetfile "GPS_IMU_SENSORS.kicad_sch")
		(duplicate_pad_numbers_are_jumpers no)
		(pad "1" smd rect
			(at -0.7 0 180)
			(size 1.1 1.05)
			(layers "F.Cu" "F.Mask" "F.Paste")
			(net "GND")
		)
		(pad "2" smd rect
			(at 0.7 0 180)
			(size 1.1 1.05)
			(layers "F.Cu" "F.Mask" "F.Paste")
			(net "+3.3V")
		)
	)
	(footprint "Passives:SOT65P210X110-3N"
		(layer "F.Cu")
		(at 195.08636 143.47763)
		(property "Reference" "D6"
			(at -3.16026 -1.068085 0)
			(unlocked yes)
			(layer "F.SilkS")
			(effects
				(font
					(size 0.762 0.762)
					(thickness 0.2286)
				)
				(justify left bottom)
			)
		)
		(property "Value" "BAT54SW"
			(at -4.0249 -1.73021 0)
			(unlocked yes)
			(layer "F.SilkS")
			(hide yes)
			(effects
				(font
					(size 1.524 1.524)
					(thickness 0.254)
				)
				(justify left bottom)
			)
		)
		(sheetname "PCIe_JTAG")
		(sheetfile "PCIe_JTAG.kicad_sch")
		(duplicate_pad_numbers_are_jumpers no)
		(fp_line
			(start -0.325 -1.1)
			(end 0.675 -1.1)
			(stroke
				(width 0.2)
				(type solid)
			)
			(layer "F.SilkS")
		)
		(fp_line
			(start -0.325 1.1)
			(end 0.675 1.1)
			(stroke
				(width 0.2)
				(type solid)
			)
			(layer "F.SilkS")
		)
		(fp_line
			(start 0.675 -0.65)
			(end 0.675 -1.1)
			(stroke
				(width 0.2)
				(type solid)
			)
			(layer "F.SilkS")
		)
		(fp_line
			(start 0.675 1.1)
			(end 0.675 0.65)
			(stroke
				(width 0.2)
				(type solid)
			)
			(layer "F.SilkS")
		)
		(fp_circle
			(center -1.125 -1.45)
			(end -1.125 -1.575)
			(stroke
				(width 0.25)
				(type solid)
			)
			(fill no)
			(layer "F.SilkS")
		)
		(pad "1" smd rect
			(at -1.125 -0.65 90)
			(size 0.5 0.9)
			(layers "F.Cu" "F.Mask" "F.Paste")
			(net "GND")
		)
		(pad "2" smd rect
			(at -1.125 0.65 90)
			(size 0.5 0.9)
			(layers "F.Cu" "F.Mask" "F.Paste")
			(net "+3.3V")
		)
		(pad "3" smd rect
			(at 1.125 0 90)
			(size 0.5 0.9)
			(layers "F.Cu" "F.Mask" "F.Paste")
			(net "FPGA_TDO")
		)
	)
	(footprint "Passives:IND_PM124SH"
		(layer "F.Cu")
		(at 215.2515 124.9422 180)
		(property "Reference" "L1"
			(at 8.2254 -1.667345 0)
			(unlocked yes)
			(layer "F.SilkS")
			(effects
				(font
					(size 0.762 0.762)
					(thickness 0.2286)
				)
				(justify left bottom)
			)
		)
		(property "Value" "PM124SH-100M-RC"
			(at 22.7845 -1.30319 0)
			(unlocked yes)
			(layer "F.SilkS")
			(hide yes)
			(effects
				(font
					(size 1.524 1.524)
					(thickness 0.254)
				)
				(justify left bottom)
			)
		)
		(sheetname "POWER")
		(sheetfile "POWER.kicad_sch")
		(duplicate_pad_numbers_are_jumpers no)
		(fp_line
			(start 6.681 6.4)
			(end -6.681 6.4)
			(stroke
				(width 0.254)
				(type solid)
			)
			(layer "F.SilkS")
		)
		(fp_line
			(start 6.681 -6.4)
			(end 6.681 6.4)
			(stroke
				(width 0.254)
				(type solid)
			)
			(layer "F.SilkS")
		)
		(fp_line
			(start 6.681 -6.4)
			(end -6.681 -6.4)
			(stroke
				(width 0.254)
				(type solid)
			)
			(layer "F.SilkS")
		)
		(fp_line
			(start -6.681 -6.4)
			(end -6.681 6.4)
			(stroke
				(width 0.254)
				(type solid)
			)
			(layer "F.SilkS")
		)
		(pad "1" smd rect
			(at -4.85 0 180)
			(size 2.9 5.4)
			(layers "F.Cu" "F.Mask" "F.Paste")
			(net "+5.0V")
		)
		(pad "2" smd rect
			(at 4.85 0 180)
			(size 2.9 5.4)
			(layers "F.Cu" "F.Mask" "F.Paste")
			(net "NetC4_2")
		)
	)
	(footprint "GNSS:GNSS"
		(locked yes)
		(layer "F.Cu")
		(at 84.1536 70.8286)
		(property "Reference" "U9"
			(at -0.6275 -5.419055 0)
			(unlocked yes)
			(layer "F.SilkS")
			(effects
				(font
					(size 0.762 0.762)
					(thickness 0.2286)
				)
				(justify left bottom)
			)
		)
		(property "Value" "RCB-F9T"
			(at -9.8007 23.16699 0)
			(unlocked yes)
			(layer "F.SilkS")
			(hide yes)
			(effects
				(font
					(size 1.524 1.524)
					(thickness 0.254)
				)
				(justify left bottom)
			)
		)
		(sheetname "GPS_IMU_SENSORS")
		(sheetfile "GPS_IMU_SENSORS.kicad_sch")
		(duplicate_pad_numbers_are_jumpers no)
		(fp_line
			(start -6.11 -20.47)
			(end 61.07 -20.47)
			(stroke
				(width 0.254)
				(type solid)
			)
			(layer "F.SilkS")
		)
		(fp_line
			(start -6.11 11.28)
			(end -6.11 -20.47)
			(stroke
				(width 0.254)
				(type solid)
			)
			(layer "F.SilkS")
		)
		(fp_line
			(start -6.11 11.28)
			(end 61.07 11.28)
			(stroke
				(width 0.254)
				(type solid)
			)
			(layer "F.SilkS")
		)
		(fp_line
			(start 61.07 11.28)
			(end 61.07 -20.47)
			(stroke
				(width 0.254)
				(type solid)
			)
			(layer "F.SilkS")
		)
		(pad "0" thru_hole circle
			(at 0 -2 270)
			(size 0 0)
			(drill 0.76)
			(layers "*.Cu" "*.Mask")
			(remove_unused_layers no)
			(thermal_bridge_angle 90)
		)
		(pad "0" thru_hole circle
			(at 0 2 270)
			(size 0 0)
			(drill 0.76)
			(layers "*.Cu" "*.Mask")
			(remove_unused_layers no)
			(thermal_bridge_angle 90)
		)
		(pad "1" smd rect
			(at -2.2225 3 270)
			(size 1.12 2.105)
			(layers "F.Cu" "F.Mask" "F.Paste")
			(net "+5.0V")
		)
		(pad "2" smd rect
			(at 2.2225 3 270)
			(size 1.12 2.105)
			(layers "F.Cu" "F.Mask" "F.Paste")
			(net "+3.3V")
		)
		(pad "3" smd rect
			(at -2.2225 1 270)
			(size 1.12 2.105)
			(layers "F.Cu" "F.Mask" "F.Paste")
			(net "GPS1_TX")
		)
		(pad "4" smd rect
			(at 2.2225 1 270)
			(size 1.12 2.105)
			(layers "F.Cu" "F.Mask" "F.Paste")
			(net "GPS1_RST")
		)
		(pad "5" smd rect
			(at -2.2225 -1 270)
			(size 1.12 2.105)
			(layers "F.Cu" "F.Mask" "F.Paste")
			(net "GPS1_RX")
		)
		(pad "6" smd rect
			(at 2.2225 -1 270)
			(size 1.12 2.105)
			(layers "F.Cu" "F.Mask" "F.Paste")
			(net "GPS1_TP1")
		)
		(pad "7" smd rect
			(at -2.2225 -3 270)
			(size 1.12 2.105)
			(layers "F.Cu" "F.Mask" "F.Paste")
			(net "GPS1_TP2")
		)
		(pad "8" smd rect
			(at 2.2225 -3 270)
			(size 1.12 2.105)
			(layers "F.Cu" "F.Mask" "F.Paste")
			(net "GND")
		)
	)
	(footprint "Vault:FP-RC0603-0_55-MFG"
		(layer "F.Cu")
		(at 84.1261 83.8662 -90)
		(property "Reference" "R40"
			(at 0.0214 3.473069 90)
			(unlocked yes)
			(layer "F.SilkS")
			(effects
				(font
					(size 0.762 0.762)
					(thickness 0.2286)
				)
			)
		)
		(property "Value" "100k"
			(at -3.089402 2.39948 180)
			(unlocked yes)
			(layer "F.SilkS")
			(hide yes)
			(effects
				(font
					(size 1.524 1.524)
					(thickness 0.254)
				)
			)
		)
		(sheetname "USER_IO_STATUS")
		(sheetfile "USER_IO_STATUS.kicad_sch")
		(duplicate_pad_numbers_are_jumpers no)
		(fp_line
			(start 0.025 0.45)
			(end -0.025 0.45)
			(stroke
				(width 0.2)
				(type solid)
			)
			(layer "F.SilkS")
		)
		(fp_line
			(start 0.025 -0.45)
			(end -0.025 -0.45)
			(stroke
				(width 0.2)
				(type solid)
			)
			(layer "F.SilkS")
		)
		(fp_line
			(start -1.4 0.55)
			(end -1.4 -0.55)
			(stroke
				(width 0.2)
				(type solid)
			)
			(layer "F.CrtYd")
		)
		(fp_line
			(start 1.4 0.55)
			(end -1.4 0.55)
			(stroke
				(width 0.2)
				(type solid)
			)
			(layer "F.CrtYd")
		)
		(fp_line
			(start 1.4 0.55)
			(end 1.4 -0.55)
			(stroke
				(width 0.2)
				(type solid)
			)
			(layer "F.CrtYd")
		)
		(fp_line
			(start 1.4 -0.55)
			(end -1.4 -0.55)
			(stroke
				(width 0.2)
				(type solid)
			)
			(layer "F.CrtYd")
		)
		(fp_line
			(start -1.4 0.55)
			(end -1.4 -0.55)
			(stroke
				(width 0.2)
				(type solid)
			)
			(layer "F.Fab")
		)
		(fp_line
			(start 1.4 0.55)
			(end -1.4 0.55)
			(stroke
				(width 0.2)
				(type solid)
			)
			(layer "F.Fab")
		)
		(fp_line
			(start 1.4 0.55)
			(end 1.4 -0.55)
			(stroke
				(width 0.2)
				(type solid)
			)
			(layer "F.Fab")
		)
		(fp_line
			(start 0 0.5)
			(end 0 -0.5)
			(stroke
				(width 0.1)
				(type solid)
			)
			(layer "F.Fab")
		)
		(fp_line
			(start 0.5 0)
			(end -0.5 0)
			(stroke
				(width 0.1)
				(type solid)
			)
			(layer "F.Fab")
		)
		(fp_line
			(start 1.4 -0.55)
			(end -1.4 -0.55)
			(stroke
				(width 0.2)
				(type solid)
			)
			(layer "F.Fab")
		)
		(pad "1" smd rect
			(at -0.85 0 270)
			(size 0.9 0.8)
			(layers "F.Cu" "F.Mask" "F.Paste")
			(net "GND")
			(solder_mask_margin 0)
			(solder_paste_margin 0)
		)
		(pad "2" smd rect
			(at 0.85 0 270)
			(size 0.9 0.8)
			(layers "F.Cu" "F.Mask" "F.Paste")
			(net "NetC39_2")
			(solder_mask_margin 0)
			(solder_paste_margin 0)
		)
	)
)
